# T6G (Grand Teton) — schematic netlist excerpt (pin names and nets, part order shuffled) for the footprints in the layout excerpt that follows; sources: Cadence DE-HDL packaged netlist, KiCad conversion of 04192023_DAF0TMB3IC0_F0TG_MB_C_brd_V02_OCP.brd

C507  Q_CAP  10UF 6.3V 20% X6S  pkg C0402  page 279 : A = P1V8_CPU0_RT0_1A ; B = GND
R6124  Q_RES  1K 1% EMPTY  pkg 0402LF  page 84 : A = PVDD18_S5_P0 ; B = FM_BOARD_SKU_ID0

(kicad_pcb
	(version 20260206)
	(generator "pcbnew")
	(generator_version "10.0")
	(general
		(thickness 1.6)
		(legacy_teardrops no)
	)
	(paper "A4")
	(title_block
		(title "04192023_DAF0TMB3IC0_F0TG_MB_C_brd_V02_OCP.brd")
		(comment 1 "Grand Teton / footprints 5564-5565 of 8354")
	)
	(layers
		(0 "F.Cu" signal "TOP")
		(4 "In1.Cu" signal "GND")
		(6 "In2.Cu" signal "IN1")
		(8 "In3.Cu" signal "GND1")
		(10 "In4.Cu" signal "IN2")
		(12 "In5.Cu" signal "GND2")
		(14 "In6.Cu" signal "IN3")
		(16 "In7.Cu" signal "GND3")
		(18 "In8.Cu" signal "VCC")
		(20 "In9.Cu" signal "VCC1")
		(22 "In10.Cu" signal "GND4")
		(24 "In11.Cu" signal "IN4")
		(26 "In12.Cu" signal "GND5")
		(28 "In13.Cu" signal "IN5")
		(30 "In14.Cu" signal "GND6")
		(32 "In15.Cu" signal "IN6")
		(34 "In16.Cu" signal "GND7")
		(2 "B.Cu" signal "BOTTOM")
		(9 "F.Adhes" user "F.Adhesive")
		(11 "B.Adhes" user "B.Adhesive")
		(13 "F.Paste" user "Package Geometry/Pastemask Top")
		(15 "B.Paste" user "Package Geometry/Pastemask Bottom")
		(5 "F.SilkS" user "Ref Des/Silkscreen Top")
		(7 "B.SilkS" user "Ref Des/Silkscreen Bottom")
		(1 "F.Mask" user "Board Geometry/Soldermask Top")
		(3 "B.Mask" user "Board Geometry/Soldermask Bottom")
		(17 "Dwgs.User" user "User.Drawings")
		(19 "Cmts.User" user "User.Comments")
		(21 "Eco1.User" user "User.Eco1")
		(23 "Eco2.User" user "User.Eco2")
		(25 "Edge.Cuts" user "Board Geometry/Outline")
		(27 "Margin" user)
		(31 "F.CrtYd" user "Package Geometry/Place Bound Top")
		(29 "B.CrtYd" user "Package Geometry/Place Bound Bottom")
		(35 "F.Fab" user "Ref Des/Assembly Top")
		(33 "B.Fab" user "Ref Des/Assembly Bottom")
	)
	(footprint ""
		(layer "B.Cu")
		(at 312.990992 -398.942052 90)
		(property "Reference" "C507"
			(at 0 0 90)
			(layer "B.SilkS")
			(hide yes)
			(effects
				(font
					(size 1.27 1.27)
				)
				(justify mirror)
			)
		)
		(property "Value" ""
			(at 0 0 90)
			(layer "B.Fab")
			(effects
				(font
					(size 1.27 1.27)
				)
				(justify mirror)
			)
		)
		(duplicate_pad_numbers_are_jumpers no)
		(fp_line
			(start 0.7874 -0.4064)
			(end -0.7874 -0.4064)
			(stroke
				(width 0.1524)
				(type default)
			)
			(layer "B.SilkS")
		)
		(fp_line
			(start -0.7874 -0.4064)
			(end -0.7874 0.4064)
			(stroke
				(width 0.1524)
				(type default)
			)
			(layer "B.SilkS")
		)
		(fp_line
			(start 0.7874 0.4064)
			(end 0.7874 -0.4064)
			(stroke
				(width 0.1524)
				(type default)
			)
			(layer "B.SilkS")
		)
		(fp_line
			(start -0.7874 0.4064)
			(end 0.7874 0.4064)
			(stroke
				(width 0.1524)
				(type default)
			)
			(layer "B.SilkS")
		)
		(fp_line
			(start 0.67945 -0.305054)
			(end 0.12065 -0.305054)
			(stroke
				(width 0.1)
				(type default)
			)
			(layer "B.Fab")
		)
		(fp_line
			(start 0.12065 -0.305054)
			(end 0.12065 -0.2794)
			(stroke
				(width 0.1)
				(type default)
			)
			(layer "B.Fab")
		)
		(fp_line
			(start -0.12065 -0.3048)
			(end -0.67945 -0.3048)
			(stroke
				(width 0.1)
				(type default)
			)
			(layer "B.Fab")
		)
		(fp_line
			(start -0.67945 -0.3048)
			(end -0.67945 0.3048)
			(stroke
				(width 0.1)
				(type default)
			)
			(layer "B.Fab")
		)
		(fp_line
			(start 0.12065 -0.2794)
			(end -0.12065 -0.2794)
			(stroke
				(width 0.1)
				(type default)
			)
			(layer "B.Fab")
		)
		(fp_line
			(start -0.12065 -0.2794)
			(end -0.12065 -0.3048)
			(stroke
				(width 0.1)
				(type default)
			)
			(layer "B.Fab")
		)
		(fp_line
			(start 0.12065 0.2794)
			(end 0.12065 0.3048)
			(stroke
				(width 0.1)
				(type default)
			)
			(layer "B.Fab")
		)
		(fp_line
			(start -0.120396 0.2794)
			(end 0.12065 0.2794)
			(stroke
				(width 0.1)
				(type default)
			)
			(layer "B.Fab")
		)
		(fp_line
			(start 0.67945 0.3048)
			(end 0.67945 -0.305054)
			(stroke
				(width 0.1)
				(type default)
			)
			(layer "B.Fab")
		)
		(fp_line
			(start 0.12065 0.3048)
			(end 0.67945 0.3048)
			(stroke
				(width 0.1)
				(type default)
			)
			(layer "B.Fab")
		)
		(fp_line
			(start -0.120396 0.3048)
			(end -0.120396 0.2794)
			(stroke
				(width 0.1)
				(type default)
			)
			(layer "B.Fab")
		)
		(fp_line
			(start -0.67945 0.3048)
			(end -0.120396 0.3048)
			(stroke
				(width 0.1)
				(type default)
			)
			(layer "B.Fab")
		)
		(pad "1" smd circle
			(at 0.40005 0 270)
			(size 0 0)
			(layers "B.Cu" "B.Mask" "B.Paste")
			(net "P1V8_CPU0_RT0_1A")
		)
		(pad "2" smd circle
			(at -0.40005 0 270)
			(size 0 0)
			(layers "B.Cu" "B.Mask" "B.Paste")
			(net "GND")
		)
	)
	(footprint ""
		(layer "B.Cu")
		(at 401.619974 -349.217742 -90)
		(property "Reference" "R6124"
			(at 0 0 90)
			(layer "B.SilkS")
			(hide yes)
			(effects
				(font
					(size 1.27 1.27)
				)
				(justify mirror)
			)
		)
		(property "Value" ""
			(at 0 0 90)
			(layer "B.Fab")
			(effects
				(font
					(size 1.27 1.27)
				)
				(justify mirror)
			)
		)
		(duplicate_pad_numbers_are_jumpers no)
		(fp_line
			(start -0.7874 0.4064)
			(end 0.7874 0.4064)
			(stroke
				(width 0.1524)
				(type default)
			)
			(layer "B.SilkS")
		)
		(fp_line
			(start 0.7874 0.4064)
			(end 0.7874 -0.4064)
			(stroke
				(width 0.1524)
				(type default)
			)
			(layer "B.SilkS")
		)
		(fp_line
			(start -0.7874 -0.4064)
			(end -0.7874 0.4064)
			(stroke
				(width 0.1524)
				(type default)
			)
			(layer "B.SilkS")
		)
		(fp_line
			(start 0.7874 -0.4064)
			(end -0.7874 -0.4064)
			(stroke
				(width 0.1524)
				(type default)
			)
			(layer "B.SilkS")
		)
		(fp_line
			(start -0.67945 0.3048)
			(end -0.120396 0.3048)
			(stroke
				(width 0.1)
				(type default)
			)
			(layer "B.Fab")
		)
		(fp_line
			(start -0.120396 0.3048)
			(end -0.120396 0.2794)
			(stroke
				(width 0.1)
				(type default)
			)
			(layer "B.Fab")
		)
		(fp_line
			(start 0.12065 0.3048)
			(end 0.67945 0.3048)
			(stroke
				(width 0.1)
				(type default)
			)
			(layer "B.Fab")
		)
		(fp_line
			(start 0.67945 0.3048)
			(end 0.67945 -0.305054)
			(stroke
				(width 0.1)
				(type default)
			)
			(layer "B.Fab")
		)
		(fp_line
			(start -0.120396 0.2794)
			(end 0.12065 0.2794)
			(stroke
				(width 0.1)
				(type default)
			)
			(layer "B.Fab")
		)
		(fp_line
			(start 0.12065 0.2794)
			(end 0.12065 0.3048)
			(stroke
				(width 0.1)
				(type default)
			)
			(layer "B.Fab")
		)
		(fp_line
			(start -0.12065 -0.2794)
			(end -0.12065 -0.3048)
			(stroke
				(width 0.1)
				(type default)
			)
			(layer "B.Fab")
		)
		(fp_line
			(start 0.12065 -0.2794)
			(end -0.12065 -0.2794)
			(stroke
				(width 0.1)
				(type default)
			)
			(layer "B.Fab")
		)
		(fp_line
			(start -0.67945 -0.3048)
			(end -0.67945 0.3048)
			(stroke
				(width 0.1)
				(type default)
			)
			(layer "B.Fab")
		)
		(fp_line
			(start -0.12065 -0.3048)
			(end -0.67945 -0.3048)
			(stroke
				(width 0.1)
				(type default)
			)
			(layer "B.Fab")
		)
		(fp_line
			(start 0.12065 -0.305054)
			(end 0.12065 -0.2794)
			(stroke
				(width 0.1)
				(type default)
			)
			(layer "B.Fab")
		)
		(fp_line
			(start 0.67945 -0.305054)
			(end 0.12065 -0.305054)
			(stroke
				(width 0.1)
				(type default)
			)
			(layer "B.Fab")
		)
		(pad "1" smd circle
			(at 0.40005 0 90)
			(size 0 0)
			(layers "B.Cu" "B.Mask" "B.Paste")
			(net "PVDD18_S5_P0")
		)
		(pad "2" smd circle
			(at -0.40005 0 90)
			(size 0 0)
			(layers "B.Cu" "B.Mask" "B.Paste")
			(net "FM_BOARD_SKU_ID0")
		)
	)
)
